(lib_symbols
	(symbol "Capacitors0402:C_100n_16V_X7R_0402"
			(pin_numbers
				(hide yes)
			)
			(pin_names
				(hide yes)
			)
			(exclude_from_sim no)
			(in_bom yes)
			(on_board yes)
			(property "Reference" "C"
				(at 15.24 -5.08 0)
				(effects
					(font
						(size 1.27 1.27)
						(thickness 0.15)
					)
					(justify left bottom)
				)
			)
			(property "Value" "C_100n_16V_X7R_0402"
				(at 15.24 -22.86 0)
				(effects
					(font
						(size 1.27 1.27)
						(thickness 0.15)
					)
					(justify left bottom)
					(hide yes)
				)
			)
			(property "Footprint" "antmicro-footprints:C_0402_1005Metric"
				(at 15.24 -25.4 0)
				(effects
					(font
						(size 1.27 1.27)
						(thickness 0.15)
					)
					(justify left bottom)
					(hide yes)
				)
			)
			(property "Datasheet" "https://www.kemet.com/en/us/capacitors/product/C0402C104J4RAC7411.html"
				(at 15.24 -27.94 0)
				(effects
					(font
						(size 1.27 1.27)
						(thickness 0.15)
					)
					(justify left bottom)
					(hide yes)
				)
			)
			(property "Description" "SMD Multilayer Ceramic Capacitor, 100nF, 50V, 0402, ±5%, X7R"
				(at 0 0 0)
				(effects
					(font
						(size 1.27 1.27)
					)
					(hide yes)
				)
			)
			(property "MPN" "C0402C104J4RAC7411"
				(at 15.24 -30.48 0)
				(effects
					(font
						(size 1.27 1.27)
						(thickness 0.15)
					)
					(justify left bottom)
					(hide yes)
				)
			)
			(property "Val" "100n"
				(at 15.24 -7.62 0)
				(effects
					(font
						(size 1.27 1.27)
						(thickness 0.15)
					)
					(justify left bottom)
				)
			)
			(property "Voltage" "16V"
				(at 15.24 -10.16 0)
				(effects
					(font
						(size 1.27 1.27)
						(thickness 0.15)
					)
					(justify left bottom)
					(hide yes)
				)
			)
			(property "Dielectric" "X7R"
				(at 15.24 -12.7 0)
				(effects
					(font
						(size 1.27 1.27)
						(thickness 0.15)
					)
					(justify left bottom)
					(hide yes)
				)
			)
			(property "Manufacturer" "KEMET"
				(at 15.24 -15.24 0)
				(effects
					(font
						(size 1.27 1.27)
						(thickness 0.15)
					)
					(justify left bottom)
					(hide yes)
				)
			)
			(property "License" "Apache-2.0"
				(at 15.24 -17.78 0)
				(effects
					(font
						(size 1.27 1.27)
						(thickness 0.15)
					)
					(justify left bottom)
					(hide yes)
				)
			)
			(property "Author" "Antmicro"
				(at 15.24 -20.32 0)
				(effects
					(font
						(size 1.27 1.27)
						(thickness 0.15)
					)
					(justify left bottom)
					(hide yes)
				)
			)
			(property "ki_keywords" "SMT, CAPACITOR, PASSIVE"
				(at 0 0 0)
				(effects
					(font
						(size 1.27 1.27)
					)
					(hide yes)
				)
			)
			(symbol "C_100n_16V_X7R_0402_0_1"
				(polyline
					(pts
						(xy 2.032 -1.524) (xy 2.032 1.524)
					)
					(stroke
						(width 0.3048)
						(type default)
					)
					(fill
						(type none)
					)
				)
				(polyline
					(pts
						(xy 3.048 -1.524) (xy 3.048 1.524)
					)
					(stroke
						(width 0.3302)
						(type default)
					)
					(fill
						(type none)
					)
				)
			)
			(symbol "C_100n_16V_X7R_0402_1_1"
				(pin passive line
					(at 0 0 0)
					(length 2.032)
					(name "~"
						(effects
							(font
								(size 1.27 1.27)
							)
						)
					)
					(number "1"
						(effects
							(font
								(size 1.27 1.27)
							)
						)
					)
				)
				(pin passive line
					(at 5.08 0 180)
					(length 2.032)
					(name "~"
						(effects
							(font
								(size 1.27 1.27)
							)
						)
					)
					(number "2"
						(effects
							(font
								(size 1.27 1.27)
							)
						)
					)
				)
			)
		)
	(symbol "EdgeConnectors:PCB-Edge_M.2_Key-M"
			(exclude_from_sim no)
			(in_bom no)
			(on_board yes)
			(property "Reference" "J"
				(at 53.34 -2.54 0)
				(effects
					(font
						(size 1.27 1.27)
						(thickness 0.15)
					)
					(justify left bottom)
				)
			)
			(property "Value" "PCB-Edge_M.2_Key-M"
				(at 53.34 -5.08 0)
				(effects
					(font
						(size 1.27 1.27)
						(thickness 0.15)
					)
					(justify left bottom)
				)
			)
			(property "Footprint" "antmicro-footprints:PCB-Edge_M.2_Key-M"
				(at 53.34 -7.62 0)
				(effects
					(font
						(size 1.27 1.27)
						(thickness 0.15)
					)
					(justify left bottom)
					(hide yes)
				)
			)
			(property "Datasheet" "https://www.amphenol-icc.com/media/wysiwyg/files/drawing/10130618.pdf"
				(at 53.34 -10.16 0)
				(effects
					(font
						(size 1.27 1.27)
						(thickness 0.15)
					)
					(justify left bottom)
					(hide yes)
				)
			)
			(property "Description" "PCB Edge for M.2 key M"
				(at 0 0 0)
				(effects
					(font
						(size 1.27 1.27)
					)
					(hide yes)
				)
			)
			(property "Author" "Antmicro"
				(at 53.34 -12.7 0)
				(effects
					(font
						(size 1.27 1.27)
						(thickness 0.15)
					)
					(justify left bottom)
					(hide yes)
				)
			)
			(property "License" "Apache-2.0"
				(at 53.34 -15.24 0)
				(effects
					(font
						(size 1.27 1.27)
						(thickness 0.15)
					)
					(justify left bottom)
					(hide yes)
				)
			)
			(property "ki_keywords" "PCB, EDGE, M.2"
				(at 0 0 0)
				(effects
					(font
						(size 1.27 1.27)
					)
					(hide yes)
				)
			)
			(symbol "PCB-Edge_M.2_Key-M_1_1"
				(rectangle
					(start 2.54 2.54)
					(end 35.56 -63.5)
					(stroke
						(width 0.254)
						(type solid)
					)
					(fill
						(type background)
					)
				)
				(text "M.2 Mechanical Key M"
					(at 7.62 -1.27 0)
					(effects
						(font
							(size 1.27 1.27)
							(thickness 0.15)
						)
						(justify left bottom)
					)
				)
				(pin power_in line
					(at 0 0 0)
					(length 2.54)
					(name "3.3V"
						(effects
							(font
								(size 1.27 1.27)
							)
						)
					)
					(number "12"
						(effects
							(font
								(size 1.27 1.27)
							)
						)
					)
				)
				(pin passive line
					(at 0 0 0)
					(length 2.54)
					(hide yes)
					(name "3.3V"
						(effects
							(font
								(size 1.27 1.27)
							)
						)
					)
					(number "14"
						(effects
							(font
								(size 1.27 1.27)
							)
						)
					)
				)
				(pin passive line
					(at 0 0 0)
					(length 2.54)
					(hide yes)
					(name "3.3V"
						(effects
							(font
								(size 1.27 1.27)
							)
						)
					)
					(number "16"
						(effects
							(font
								(size 1.27 1.27)
							)
						)
					)
				)
				(pin passive line
					(at 0 0 0)
					(length 2.54)
					(hide yes)
					(name "3.3V"
						(effects
							(font
								(size 1.27 1.27)
							)
						)
					)
					(number "18"
						(effects
							(font
								(size 1.27 1.27)
							)
						)
					)
				)
				(pin passive line
					(at 0 0 0)
					(length 2.54)
					(hide yes)
					(name "3.3V"
						(effects
							(font
								(size 1.27 1.27)
							)
						)
					)
					(number "2"
						(effects
							(font
								(size 1.27 1.27)
							)
						)
					)
				)
				(pin passive line
					(at 0 0 0)
					(length 2.54)
					(hide yes)
					(name "3.3V"
						(effects
							(font
								(size 1.27 1.27)
							)
						)
					)
					(number "4"
						(effects
							(font
								(size 1.27 1.27)
							)
						)
					)
				)
				(pin passive line
					(at 0 0 0)
					(length 2.54)
					(hide yes)
					(name "3.3V"
						(effects
							(font
								(size 1.27 1.27)
							)
						)
					)
					(number "70"
						(effects
							(font
								(size 1.27 1.27)
							)
						)
					)
				)
				(pin passive line
					(at 0 0 0)
					(length 2.54)
					(hide yes)
					(name "3.3V"
						(effects
							(font
								(size 1.27 1.27)
							)
						)
					)
					(number "72"
						(effects
							(font
								(size 1.27 1.27)
							)
						)
					)
				)
				(pin passive line
					(at 0 0 0)
					(length 2.54)
					(hide yes)
					(name "3.3V"
						(effects
							(font
								(size 1.27 1.27)
							)
						)
					)
					(number "74"
						(effects
							(font
								(size 1.27 1.27)
							)
						)
					)
				)
				(pin passive line
					(at 0 -3.81 0)
					(length 2.54)
					(name "PERp3"
						(effects
							(font
								(size 1.27 1.27)
							)
						)
					)
					(number "7"
						(effects
							(font
								(size 1.27 1.27)
							)
						)
					)
				)
				(pin passive line
					(at 0 -6.35 0)
					(length 2.54)
					(name "PERn3"
						(effects
							(font
								(size 1.27 1.27)
							)
						)
					)
					(number "5"
						(effects
							(font
								(size 1.27 1.27)
							)
						)
					)
				)
				(pin passive line
					(at 0 -10.16 0)
					(length 2.54)
					(name "PETp3"
						(effects
							(font
								(size 1.27 1.27)
							)
						)
					)
					(number "13"
						(effects
							(font
								(size 1.27 1.27)
							)
						)
					)
				)
				(pin passive line
					(at 0 -12.7 0)
					(length 2.54)
					(name "PETn3"
						(effects
							(font
								(size 1.27 1.27)
							)
						)
					)
					(number "11"
						(effects
							(font
								(size 1.27 1.27)
							)
						)
					)
				)
				(pin passive line
					(at 0 -16.51 0)
					(length 2.54)
					(name "PERp2"
						(effects
							(font
								(size 1.27 1.27)
							)
						)
					)
					(number "19"
						(effects
							(font
								(size 1.27 1.27)
							)
						)
					)
				)
				(pin passive line
					(at 0 -19.05 0)
					(length 2.54)
					(name "PERn2"
						(effects
							(font
								(size 1.27 1.27)
							)
						)
					)
					(number "17"
						(effects
							(font
								(size 1.27 1.27)
							)
						)
					)
				)
				(pin passive line
					(at 0 -22.86 0)
					(length 2.54)
					(name "PETp2"
						(effects
							(font
								(size 1.27 1.27)
							)
						)
					)
					(number "25"
						(effects
							(font
								(size 1.27 1.27)
							)
						)
					)
				)
				(pin passive line
					(at 0 -25.4 0)
					(length 2.54)
					(name "PETn2"
						(effects
							(font
								(size 1.27 1.27)
							)
						)
					)
					(number "23"
						(effects
							(font
								(size 1.27 1.27)
							)
						)
					)
				)
				(pin passive line
					(at 0 -29.21 0)
					(length 2.54)
					(name "PERp1"
						(effects
							(font
								(size 1.27 1.27)
							)
						)
					)
					(number "31"
						(effects
							(font
								(size 1.27 1.27)
							)
						)
					)
				)
				(pin passive line
					(at 0 -31.75 0)
					(length 2.54)
					(name "PERn1"
						(effects
							(font
								(size 1.27 1.27)
							)
						)
					)
					(number "29"
						(effects
							(font
								(size 1.27 1.27)
							)
						)
					)
				)
				(pin passive line
					(at 0 -35.56 0)
					(length 2.54)
					(name "PETp1"
						(effects
							(font
								(size 1.27 1.27)
							)
						)
					)
					(number "37"
						(effects
							(font
								(size 1.27 1.27)
							)
						)
					)
				)
				(pin passive line
					(at 0 -38.1 0)
					(length 2.54)
					(name "PETn1"
						(effects
							(font
								(size 1.27 1.27)
							)
						)
					)
					(number "35"
						(effects
							(font
								(size 1.27 1.27)
							)
						)
					)
				)
				(pin passive line
					(at 0 -41.91 0)
					(length 2.54)
					(name "SATA-B+"
						(effects
							(font
								(size 1.27 1.27)
							)
						)
					)
					(number "43"
						(effects
							(font
								(size 1.27 1.27)
							)
						)
					)
					(alternate "PERp0" passive line)
				)
				(pin passive line
					(at 0 -44.45 0)
					(length 2.54)
					(name "SATA-B-"
						(effects
							(font
								(size 1.27 1.27)
							)
						)
					)
					(number "41"
						(effects
							(font
								(size 1.27 1.27)
							)
						)
					)
					(alternate "PERn0" passive line)
				)
				(pin passive line
					(at 0 -48.26 0)
					(length 2.54)
					(name "SATA-A+"
						(effects
							(font
								(size 1.27 1.27)
							)
						)
					)
					(number "49"
						(effects
							(font
								(size 1.27 1.27)
							)
						)
					)
					(alternate "PETp0" passive line)
				)
				(pin passive line
					(at 0 -50.8 0)
					(length 2.54)
					(name "SATA-A-"
						(effects
							(font
								(size 1.27 1.27)
							)
						)
					)
					(number "47"
						(effects
							(font
								(size 1.27 1.27)
							)
						)
					)
					(alternate "PETn0" passive line)
				)
				(pin passive line
					(at 0 -54.61 0)
					(length 2.54)
					(name "REFCLKp"
						(effects
							(font
								(size 1.27 1.27)
							)
						)
					)
					(number "55"
						(effects
							(font
								(size 1.27 1.27)
							)
						)
					)
				)
				(pin passive line
					(at 0 -57.15 0)
					(length 2.54)
					(name "REFCLKn"
						(effects
							(font
								(size 1.27 1.27)
							)
						)
					)
					(number "53"
						(effects
							(font
								(size 1.27 1.27)
							)
						)
					)
				)
				(pin passive line
					(at 0 -60.96 0)
					(length 2.54)
					(name "PEDET"
						(effects
							(font
								(size 1.27 1.27)
							)
						)
					)
					(number "69"
						(effects
							(font
								(size 1.27 1.27)
							)
						)
					)
				)
				(pin no_connect line
					(at 35.56 -15.24 180)
					(length 2.54)
					(hide yes)
					(name "NC"
						(effects
							(font
								(size 1.27 1.27)
							)
						)
					)
					(number "67"
						(effects
							(font
								(size 1.27 1.27)
							)
						)
					)
					(alternate "A" passive line)
				)
				(pin no_connect line
					(at 35.56 -16.51 180)
					(length 2.54)
					(hide yes)
					(name "NC"
						(effects
							(font
								(size 1.27 1.27)
							)
						)
					)
					(number "6"
						(effects
							(font
								(size 1.27 1.27)
							)
						)
					)
				)
				(pin no_connect line
					(at 35.56 -17.78 180)
					(length 2.54)
					(hide yes)
					(name "NC"
						(effects
							(font
								(size 1.27 1.27)
							)
						)
					)
					(number "8"
						(effects
							(font
								(size 1.27 1.27)
							)
						)
					)
				)
				(pin no_connect line
					(at 35.56 -19.05 180)
					(length 2.54)
					(hide yes)
					(name "NC"
						(effects
							(font
								(size 1.27 1.27)
							)
						)
					)
					(number "20"
						(effects
							(font
								(size 1.27 1.27)
							)
						)
					)
				)
				(pin no_connect line
					(at 35.56 -20.32 180)
					(length 2.54)
					(hide yes)
					(name "NC"
						(effects
							(font
								(size 1.27 1.27)
							)
						)
					)
					(number "22"
						(effects
							(font
								(size 1.27 1.27)
							)
						)
					)
				)
				(pin no_connect line
					(at 35.56 -21.59 180)
					(length 2.54)
					(hide yes)
					(name "NC"
						(effects
							(font
								(size 1.27 1.27)
							)
						)
					)
					(number "24"
						(effects
							(font
								(size 1.27 1.27)
							)
						)
					)
				)
				(pin no_connect line
					(at 35.56 -22.86 180)
					(length 2.54)
					(hide yes)
					(name "NC"
						(effects
							(font
								(size 1.27 1.27)
							)
						)
					)
					(number "26"
						(effects
							(font
								(size 1.27 1.27)
							)
						)
					)
				)
				(pin no_connect line
					(at 35.56 -24.13 180)
					(length 2.54)
					(hide yes)
					(name "NC"
						(effects
							(font
								(size 1.27 1.27)
							)
						)
					)
					(number "28"
						(effects
							(font
								(size 1.27 1.27)
							)
						)
					)
				)
				(pin no_connect line
					(at 35.56 -25.4 180)
					(length 2.54)
					(hide yes)
					(name "NC"
						(effects
							(font
								(size 1.27 1.27)
							)
						)
					)
					(number "30"
						(effects
							(font
								(size 1.27 1.27)
							)
						)
					)
				)
				(pin no_connect line
					(at 35.56 -26.67 180)
					(length 2.54)
					(hide yes)
					(name "NC"
						(effects
							(font
								(size 1.27 1.27)
							)
						)
					)
					(number "32"
						(effects
							(font
								(size 1.27 1.27)
							)
						)
					)
				)
				(pin no_connect line
					(at 35.56 -27.94 180)
					(length 2.54)
					(hide yes)
					(name "NC"
						(effects
							(font
								(size 1.27 1.27)
							)
						)
					)
					(number "34"
						(effects
							(font
								(size 1.27 1.27)
							)
						)
					)
				)
				(pin no_connect line
					(at 35.56 -29.21 180)
					(length 2.54)
					(hide yes)
					(name "NC"
						(effects
							(font
								(size 1.27 1.27)
							)
						)
					)
					(number "36"
						(effects
							(font
								(size 1.27 1.27)
							)
						)
					)
				)
				(pin no_connect line
					(at 35.56 -30.48 180)
					(length 2.54)
					(hide yes)
					(name "NC"
						(effects
							(font
								(size 1.27 1.27)
							)
						)
					)
					(number "40"
						(effects
							(font
								(size 1.27 1.27)
							)
						)
					)
				)
				(pin no_connect line
					(at 35.56 -31.75 180)
					(length 2.54)
					(hide yes)
					(name "NC"
						(effects
							(font
								(size 1.27 1.27)
							)
						)
					)
					(number "42"
						(effects
							(font
								(size 1.27 1.27)
							)
						)
					)
				)
				(pin no_connect line
					(at 35.56 -33.02 180)
					(length 2.54)
					(hide yes)
					(name "NC"
						(effects
							(font
								(size 1.27 1.27)
							)
						)
					)
					(number "44"
						(effects
							(font
								(size 1.27 1.27)
							)
						)
					)
				)
				(pin no_connect line
					(at 35.56 -34.29 180)
					(length 2.54)
					(hide yes)
					(name "NC"
						(effects
							(font
								(size 1.27 1.27)
							)
						)
					)
					(number "46"
						(effects
							(font
								(size 1.27 1.27)
							)
						)
					)
				)
				(pin no_connect line
					(at 35.56 -35.56 180)
					(length 2.54)
					(hide yes)
					(name "NC"
						(effects
							(font
								(size 1.27 1.27)
							)
						)
					)
					(number "48"
						(effects
							(font
								(size 1.27 1.27)
							)
						)
					)
				)
				(pin no_connect line
					(at 35.56 -36.83 180)
					(length 2.54)
					(hide yes)
					(name "NC"
						(effects
							(font
								(size 1.27 1.27)
							)
						)
					)
					(number "56"
						(effects
							(font
								(size 1.27 1.27)
							)
						)
					)
				)
				(pin no_connect line
					(at 35.56 -38.1 180)
					(length 2.54)
					(hide yes)
					(name "NC"
						(effects
							(font
								(size 1.27 1.27)
							)
						)
					)
					(number "58"
						(effects
							(font
								(size 1.27 1.27)
							)
						)
					)
				)
				(pin passive line
					(at 38.1 0 180)
					(length 2.54)
					(name "DAS"
						(effects
							(font
								(size 1.27 1.27)
							)
						)
					)
					(number "10"
						(effects
							(font
								(size 1.27 1.27)
							)
						)
					)
					(alternate "DSS#" passive line)
				)
				(pin passive line
					(at 38.1 -2.54 180)
					(length 2.54)
					(name "DEVSLP"
						(effects
							(font
								(size 1.27 1.27)
							)
						)
					)
					(number "38"
						(effects
							(font
								(size 1.27 1.27)
							)
						)
					)
				)
				(pin passive line
					(at 38.1 -5.08 180)
					(length 2.54)
					(name "PERST#"
						(effects
							(font
								(size 1.27 1.27)
							)
						)
					)
					(number "50"
						(effects
							(font
								(size 1.27 1.27)
							)
						)
					)
				)
				(pin passive line
					(at 38.1 -7.62 180)
					(length 2.54)
					(name "CLKREQ#"
						(effects
							(font
								(size 1.27 1.27)
							)
						)
					)
					(number "52"
						(effects
							(font
								(size 1.27 1.27)
							)
						)
					)
				)
				(pin passive line
					(at 38.1 -10.16 180)
					(length 2.54)
					(name "PEWAKE#"
						(effects
							(font
								(size 1.27 1.27)
							)
						)
					)
					(number "54"
						(effects
							(font
								(size 1.27 1.27)
							)
						)
					)
				)
				(pin passive line
					(at 38.1 -12.7 180)
					(length 2.54)
					(name "SUSCLK"
						(effects
							(font
								(size 1.27 1.27)
							)
						)
					)
					(number "68"
						(effects
							(font
								(size 1.27 1.27)
							)
						)
					)
				)
				(pin passive line
					(at 38.1 -60.96 180)
					(length 2.54)
					(name "GND"
						(effects
							(font
								(size 1.27 1.27)
							)
						)
					)
					(number "1"
						(effects
							(font
								(size 1.27 1.27)
							)
						)
					)
				)
				(pin passive line
					(at 38.1 -60.96 180)
					(length 2.54)
					(hide yes)
					(name "GND"
						(effects
							(font
								(size 1.27 1.27)
							)
						)
					)
					(number "15"
						(effects
							(font
								(size 1.27 1.27)
							)
						)
					)
				)
				(pin passive line
					(at 38.1 -60.96 180)
					(length 2.54)
					(hide yes)
					(name "GND"
						(effects
							(font
								(size 1.27 1.27)
							)
						)
					)
					(number "21"
						(effects
							(font
								(size 1.27 1.27)
							)
						)
					)
				)
				(pin passive line
					(at 38.1 -60.96 180)
					(length 2.54)
					(hide yes)
					(name "GND"
						(effects
							(font
								(size 1.27 1.27)
							)
						)
					)
					(number "27"
						(effects
							(font
								(size 1.27 1.27)
							)
						)
					)
				)
				(pin passive line
					(at 38.1 -60.96 180)
					(length 2.54)
					(hide yes)
					(name "GND"
						(effects
							(font
								(size 1.27 1.27)
							)
						)
					)
					(number "3"
						(effects
							(font
								(size 1.27 1.27)
							)
						)
					)
				)
				(pin passive line
					(at 38.1 -60.96 180)
					(length 2.54)
					(hide yes)
					(name "GND"
						(effects
							(font
								(size 1.27 1.27)
							)
						)
					)
					(number "33"
						(effects
							(font
								(size 1.27 1.27)
							)
						)
					)
				)
				(pin passive line
					(at 38.1 -60.96 180)
					(length 2.54)
					(hide yes)
					(name "GND"
						(effects
							(font
								(size 1.27 1.27)
							)
						)
					)
					(number "39"
						(effects
							(font
								(size 1.27 1.27)
							)
						)
					)
				)
				(pin passive line
					(at 38.1 -60.96 180)
					(length 2.54)
					(hide yes)
					(name "GND"
						(effects
							(font
								(size 1.27 1.27)
							)
						)
					)
					(number "45"
						(effects
							(font
								(size 1.27 1.27)
							)
						)
					)
				)
				(pin passive line
					(at 38.1 -60.96 180)
					(length 2.54)
					(hide yes)
					(name "GND"
						(effects
							(font
								(size 1.27 1.27)
							)
						)
					)
					(number "51"
						(effects
							(font
								(size 1.27 1.27)
							)
						)
					)
				)
				(pin passive line
					(at 38.1 -60.96 180)
					(length 2.54)
					(hide yes)
					(name "GND"
						(effects
							(font
								(size 1.27 1.27)
							)
						)
					)
					(number "57"
						(effects
							(font
								(size 1.27 1.27)
							)
						)
					)
				)
				(pin passive line
					(at 38.1 -60.96 180)
					(length 2.54)
					(hide yes)
					(name "GND"
						(effects
							(font
								(size 1.27 1.27)
							)
						)
					)
					(number "71"
						(effects
							(font
								(size 1.27 1.27)
							)
						)
					)
				)
				(pin passive line
					(at 38.1 -60.96 180)
					(length 2.54)
					(hide yes)
					(name "GND"
						(effects
							(font
								(size 1.27 1.27)
							)
						)
					)
					(number "73"
						(effects
							(font
								(size 1.27 1.27)
							)
						)
					)
				)
				(pin passive line
					(at 38.1 -60.96 180)
					(length 2.54)
					(hide yes)
					(name "GND"
						(effects
							(font
								(size 1.27 1.27)
							)
						)
					)
					(number "75"
						(effects
							(font
								(size 1.27 1.27)
							)
						)
					)
				)
				(pin passive line
					(at 38.1 -60.96 180)
					(length 2.54)
					(hide yes)
					(name "GND"
						(effects
							(font
								(size 1.27 1.27)
							)
						)
					)
					(number "9"
						(effects
							(font
								(size 1.27 1.27)
							)
						)
					)
				)
			)
		)
	(symbol "PciConnectors:OCuLink_x4_Amphenol_G14A421211112HR"
			(exclude_from_sim no)
			(in_bom yes)
			(on_board yes)
			(property "Reference" "J"
				(at 39.37 -5.08 0)
				(effects
					(font
						(size 1.27 1.27)
						(thickness 0.15)
					)
					(justify left bottom)
				)
			)
			(property "Value" "OCuLink_x4_Amphenol_G14A421211112HR"
				(at 39.37 -12.7 0)
				(effects
					(font
						(size 1.27 1.27)
						(thickness 0.15)
					)
					(justify left bottom)
					(hide yes)
				)
			)
			(property "Footprint" "antmicro-footprints:Amphenol_G14A421211112HR"
				(at 39.37 -15.24 0)
				(effects
					(font
						(size 1.27 1.27)
						(thickness 0.15)
					)
					(justify left bottom)
					(hide yes)
				)
			)
			(property "Datasheet" "https://cdn.amphenol-cs.com/media/wysiwyg/files/drawing/g14a421x1bxxxhr.pdf"
				(at 39.37 -17.78 0)
				(effects
					(font
						(size 1.27 1.27)
						(thickness 0.15)
					)
					(justify left bottom)
					(hide yes)
				)
			)
			(property "Description" "I/O Connectors OCulink, Receptacle, 0.5mm pitch, 4X, R/A SMT with shell leg SMT type, 30U\" gold plating, LCP, black, T&R packing"
				(at 0 0 0)
				(effects
					(font
						(size 1.27 1.27)
					)
					(hide yes)
				)
			)
			(property "Manufacturer" "Amphenol"
				(at 39.37 -10.16 0)
				(effects
					(font
						(size 1.27 1.27)
						(thickness 0.15)
					)
					(justify left bottom)
					(hide yes)
				)
			)
			(property "MPN" "G14A421211112HR"
				(at 39.37 -7.62 0)
				(effects
					(font
						(size 1.27 1.27)
						(thickness 0.15)
					)
					(justify left bottom)
				)
			)
			(property "Author" "Antmicro"
				(at 39.37 -20.32 0)
				(effects
					(font
						(size 1.27 1.27)
						(thickness 0.15)
					)
					(justify left bottom)
					(hide yes)
				)
			)
			(property "License" "Apache-2.0"
				(at 39.37 -22.86 0)
				(effects
					(font
						(size 1.27 1.27)
						(thickness 0.15)
					)
					(justify left bottom)
					(hide yes)
				)
			)
			(property "ki_keywords" "SMT, CONNECTOR, PCIE"
				(at 0 0 0)
				(effects
					(font
						(size 1.27 1.27)
					)
					(hide yes)
				)
			)
			(symbol "OCuLink_x4_Amphenol_G14A421211112HR_1_1"
				(rectangle
					(start 3.81 2.54)
					(end 21.59 -93.98)
					(stroke
						(width 0.254)
						(type default)
					)
					(fill
						(type background)
					)
				)
				(pin passive line
					(at 0 0 0)
					(length 3.81)
					(name "5V"
						(effects
							(font
								(size 1.27 1.27)
							)
						)
					)
					(number "A21"
						(effects
							(font
								(size 1.27 1.27)
							)
						)
					)
				)
				(pin passive line
					(at 0 0 0)
					(length 3.81)
					(hide yes)
					(name "5V"
						(effects
							(font
								(size 1.27 1.27)
							)
						)
					)
					(number "B1"
						(effects
							(font
								(size 1.27 1.27)
							)
						)
					)
				)
				(pin power_in line
					(at 0 -2.54 0)
					(length 3.81)
					(name "V_{ACT}_RX_3V3"
						(effects
							(font
								(size 1.27 1.27)
							)
						)
					)
					(number "A1"
						(effects
							(font
								(size 1.27 1.27)
							)
						)
					)
				)
				(pin power_in line
					(at 0 -5.08 0)
					(length 3.81)
					(name "V_{ACT}_TX_3V3"
						(effects
							(font
								(size 1.27 1.27)
							)
						)
					)
					(number "B21"
						(effects
							(font
								(size 1.27 1.27)
							)
						)
					)
				)
				(pin bidirectional line
					(at 0 -10.16 0)
					(length 3.81)
					(name "SCL"
						(effects
							(font
								(size 1.27 1.27)
							)
						)
					)
					(number "B9"
						(effects
							(font
								(size 1.27 1.27)
							)
						)
					)
				)
				(pin bidirectional line
					(at 0 -12.7 0)
					(length 3.81)
					(name "SDA"
						(effects
							(font
								(size 1.27 1.27)
							)
						)
					)
					(number "B10"
						(effects
							(font
								(size 1.27 1.27)
							)
						)
					)
				)
				(pin bidirectional line
					(at 0 -17.78 0)
					(length 3.81)
					(name "VSP1"
						(effects
							(font
								(size 1.27 1.27)
							)
						)
					)
					(number "A12"
						(effects
							(font
								(size 1.27 1.27)
							)
						)
					)
				)
				(pin bidirectional line
					(at 0 -20.32 0)
					(length 3.81)
					(name "VSP2"
						(effects
							(font
								(size 1.27 1.27)
							)
						)
					)
					(number "A13"
						(effects
							(font
								(size 1.27 1.27)
							)
						)
					)
				)
				(pin bidirectional line
					(at 0 -25.4 0)
					(length 3.81)
					(name "~{PERST}"
						(effects
							(font
								(size 1.27 1.27)
							)
						)
					)
					(number "B12"
						(effects
							(font
								(size 1.27 1.27)
							)
						)
					)
				)
				(pin bidirectional line
					(at 0 -27.94 0)
					(length 3.81)
					(name "~{CPRSNT}"
						(effects
							(font
								(size 1.27 1.27)
							)
						)
					)
					(number "B13"
						(effects
							(font
								(size 1.27 1.27)
							)
						)
					)
				)
				(pin bidirectional line
					(at 0 -30.48 0)
					(length 3.81)
					(name "~{CWAKE}"
						(effects
							(font
								(size 1.27 1.27)
							)
						)
					)
					(number "A10"
						(effects
							(font
								(size 1.27 1.27)
							)
						)
					)
				)
				(pin output line
					(at 0 -35.56 0)
					(length 3.81)
					(name "PER0+"
						(effects
							(font
								(size 1.27 1.27)
							)
						)
					)
					(number "A3"
						(effects
							(font
								(size 1.27 1.27)
							)
						)
					)
				)
				(pin output line
					(at 0 -38.1 0)
					(length 3.81)
					(name "PER0-"
						(effects
							(font
								(size 1.27 1.27)
							)
						)
					)
					(number "A4"
						(effects
							(font
								(size 1.27 1.27)
							)
						)
					)
				)
				(pin output line
					(at 0 -43.18 0)
					(length 3.81)
					(name "PER1+"
						(effects
							(font
								(size 1.27 1.27)
							)
						)
					)
					(number "A6"
						(effects
							(font
								(size 1.27 1.27)
							)
						)
					)
				)
				(pin output line
					(at 0 -45.72 0)
					(length 3.81)
					(name "PER1-"
						(effects
							(font
								(size 1.27 1.27)
							)
						)
					)
					(number "A7"
						(effects
							(font
								(size 1.27 1.27)
							)
						)
					)
				)
				(pin output line
					(at 0 -50.8 0)
					(length 3.81)
					(name "PER2+"
						(effects
							(font
								(size 1.27 1.27)
							)
						)
					)
					(number "A15"
						(effects
							(font
								(size 1.27 1.27)
							)
						)
					)
				)
				(pin output line
					(at 0 -53.34 0)
					(length 3.81)
					(name "PER2-"
						(effects
							(font
								(size 1.27 1.27)
							)
						)
					)
					(number "A16"
						(effects
							(font
								(size 1.27 1.27)
							)
						)
					)
				)
				(pin output line
					(at 0 -58.42 0)
					(length 3.81)
					(name "PER3+"
						(effects
							(font
								(size 1.27 1.27)
							)
						)
					)
					(number "A18"
						(effects
							(font
								(size 1.27 1.27)
							)
						)
					)
				)
				(pin output line
					(at 0 -60.96 0)
					(length 3.81)
					(name "PER3-"
						(effects
							(font
								(size 1.27 1.27)
							)
						)
					)
					(number "A19"
						(effects
							(font
								(size 1.27 1.27)
							)
						)
					)
				)
				(pin input line
					(at 0 -66.04 0)
					(length 3.81)
					(name "PET0+"
						(effects
							(font
								(size 1.27 1.27)
							)
						)
					)
					(number "B3"
						(effects
							(font
								(size 1.27 1.27)
							)
						)
					)
				)
				(pin input line
					(at 0 -68.58 0)
					(length 3.81)
					(name "PET0-"
						(effects
							(font
								(size 1.27 1.27)
							)
						)
					)
					(number "B4"
						(effects
							(font
								(size 1.27 1.27)
							)
						)
					)
				)
				(pin input line
					(at 0 -73.66 0)
					(length 3.81)
					(name "PET1+"
						(effects
							(font
								(size 1.27 1.27)
							)
						)
					)
					(number "B6"
						(effects
							(font
								(size 1.27 1.27)
							)
						)
					)
				)
				(pin input line
					(at 0 -76.2 0)
					(length 3.81)
					(name "PET1-"
						(effects
							(font
								(size 1.27 1.27)
							)
						)
					)
					(number "B7"
						(effects
							(font
								(size 1.27 1.27)
							)
						)
					)
				)
				(pin input line
					(at 0 -81.28 0)
					(length 3.81)
					(name "PET2+"
						(effects
							(font
								(size 1.27 1.27)
							)
						)
					)
					(number "B15"
						(effects
							(font
								(size 1.27 1.27)
							)
						)
					)
				)
				(pin input line
					(at 0 -83.82 0)
					(length 3.81)
					(name "PET2-"
						(effects
							(font
								(size 1.27 1.27)
							)
						)
					)
					(number "B16"
						(effects
							(font
								(size 1.27 1.27)
							)
						)
					)
				)
				(pin input line
					(at 0 -88.9 0)
					(length 3.81)
					(name "PET3+"
						(effects
							(font
								(size 1.27 1.27)
							)
						)
					)
					(number "B18"
						(effects
							(font
								(size 1.27 1.27)
							)
						)
					)
				)
				(pin input line
					(at 0 -91.44 0)
					(length 3.81)
					(name "PET3-"
						(effects
							(font
								(size 1.27 1.27)
							)
						)
					)
					(number "B19"
						(effects
							(font
								(size 1.27 1.27)
							)
						)
					)
				)
				(pin no_connect line
					(at 21.59 -76.2 180)
					(length 3.81)
					(hide yes)
					(name "NC"
						(effects
							(font
								(size 1.27 1.27)
							)
						)
					)
					(number "A9"
						(effects
							(font
								(size 1.27 1.27)
							)
						)
					)
				)
				(pin passive line
					(at 25.4 -88.9 180)
					(length 3.81)
					(name "SH"
						(effects
							(font
								(size 1.27 1.27)
							)
						)
					)
					(number "SH"
						(effects
							(font
								(size 1.27 1.27)
							)
						)
					)
				)
				(pin passive line
					(at 25.4 -91.44 180)
					(length 3.81)
					(name "GND"
						(effects
							(font
								(size 1.27 1.27)
							)
						)
					)
					(number "A11"
						(effects
							(font
								(size 1.27 1.27)
							)
						)
					)
				)
				(pin passive line
					(at 25.4 -91.44 180)
					(length 3.81)
					(hide yes)
					(name "GND"
						(effects
							(font
								(size 1.27 1.27)
							)
						)
					)
					(number "A14"
						(effects
							(font
								(size 1.27 1.27)
							)
						)
					)
				)
				(pin passive line
					(at 25.4 -91.44 180)
					(length 3.81)
					(hide yes)
					(name "GND"
						(effects
							(font
								(size 1.27 1.27)
							)
						)
					)
					(number "A17"
						(effects
							(font
								(size 1.27 1.27)
							)
						)
					)
				)
				(pin passive line
					(at 25.4 -91.44 180)
					(length 3.81)
					(hide yes)
					(name "GND"
						(effects
							(font
								(size 1.27 1.27)
							)
						)
					)
					(number "A2"
						(effects
							(font
								(size 1.27 1.27)
							)
						)
					)
				)
				(pin passive line
					(at 25.4 -91.44 180)
					(length 3.81)
					(hide yes)
					(name "GND"
						(effects
							(font
								(size 1.27 1.27)
							)
						)
					)
					(number "A20"
						(effects
							(font
								(size 1.27 1.27)
							)
						)
					)
				)
				(pin passive line
					(at 25.4 -91.44 180)
					(length 3.81)
					(hide yes)
					(name "GND"
						(effects
							(font
								(size 1.27 1.27)
							)
						)
					)
					(number "A5"
						(effects
							(font
								(size 1.27 1.27)
							)
						)
					)
				)
				(pin passive line
					(at 25.4 -91.44 180)
					(length 3.81)
					(hide yes)
					(name "GND"
						(effects
							(font
								(size 1.27 1.27)
							)
						)
					)
					(number "A8"
						(effects
							(font
								(size 1.27 1.27)
							)
						)
					)
				)
				(pin passive line
					(at 25.4 -91.44 180)
					(length 3.81)
					(hide yes)
					(name "GND"
						(effects
							(font
								(size 1.27 1.27)
							)
						)
					)
					(number "B11"
						(effects
							(font
								(size 1.27 1.27)
							)
						)
					)
				)
				(pin passive line
					(at 25.4 -91.44 180)
					(length 3.81)
					(hide yes)
					(name "GND"
						(effects
							(font
								(size 1.27 1.27)
							)
						)
					)
					(number "B14"
						(effects
							(font
								(size 1.27 1.27)
							)
						)
					)
				)
				(pin passive line
					(at 25.4 -91.44 180)
					(length 3.81)
					(hide yes)
					(name "GND"
						(effects
							(font
								(size 1.27 1.27)
							)
						)
					)
					(number "B17"
						(effects
							(font
								(size 1.27 1.27)
							)
						)
					)
				)
				(pin passive line
					(at 25.4 -91.44 180)
					(length 3.81)
					(hide yes)
					(name "GND"
						(effects
							(font
								(size 1.27 1.27)
							)
						)
					)
					(number "B2"
						(effects
							(font
								(size 1.27 1.27)
							)
						)
					)
				)
				(pin passive line
					(at 25.4 -91.44 180)
					(length 3.81)
					(hide yes)
					(name "GND"
						(effects
							(font
								(size 1.27 1.27)
							)
						)
					)
					(number "B20"
						(effects
							(font
								(size 1.27 1.27)
							)
						)
					)
				)
				(pin passive line
					(at 25.4 -91.44 180)
					(length 3.81)
					(hide yes)
					(name "GND"
						(effects
							(font
								(size 1.27 1.27)
							)
						)
					)
					(number "B5"
						(effects
							(font
								(size 1.27 1.27)
							)
						)
					)
				)
				(pin passive line
					(at 25.4 -91.44 180)
					(length 3.81)
					(hide yes)
					(name "GND"
						(effects
							(font
								(size 1.27 1.27)
							)
						)
					)
					(number "B8"
						(effects
							(font
								(size 1.27 1.27)
							)
						)
					)
				)
			)
		)
	(symbol "Resistors0402:R_0R_0402"
			(pin_numbers
				(hide yes)
			)
			(pin_names
				(hide yes)
			)
			(exclude_from_sim no)
			(in_bom yes)
			(on_board yes)
			(property "Reference" "R"
				(at 20.32 -5.08 0)
				(effects
					(font
						(size 1.27 1.27)
						(thickness 0.15)
					)
					(justify left bottom)
				)
			)
			(property "Value" "R_0R_0402"
				(at 20.32 -12.7 0)
				(effects
					(font
						(size 1.27 1.27)
						(thickness 0.15)
					)
					(justify left bottom)
					(hide yes)
				)
			)
			(property "Footprint" "antmicro-footprints:R_0402_1005Metric"
				(at 20.32 -15.24 0)
				(effects
					(font
						(size 1.27 1.27)
						(thickness 0.15)
					)
					(justify left bottom)
					(hide yes)
				)
			)
			(property "Datasheet" "https://industrial.panasonic.com/cdbs/www-data/pdf/RDA0000/AOA0000C301.pdf"
				(at 20.32 -17.78 0)
				(effects
					(font
						(size 1.27 1.27)
						(thickness 0.15)
					)
					(justify left bottom)
					(hide yes)
				)
			)
			(property "Description" "SMD Chip Resistor, Jumper, 0 ohm, 100 mW, 0402 [1005 Metric], Thick Film, General Purpose"
				(at 0 0 0)
				(effects
					(font
						(size 1.27 1.27)
					)
					(hide yes)
				)
			)
			(property "MPN" "ERJ2GE0R00X"
				(at 20.32 -20.32 0)
				(effects
					(font
						(size 1.27 1.27)
						(thickness 0.15)
					)
					(justify left bottom)
					(hide yes)
				)
			)
			(property "Manufacturer" "Panasonic"
				(at 20.32 -22.86 0)
				(effects
					(font
						(size 1.27 1.27)
						(thickness 0.15)
					)
					(justify left bottom)
					(hide yes)
				)
			)
			(property "License" "Apache-2.0"
				(at 20.32 -25.4 0)
				(effects
					(font
						(size 1.27 1.27)
						(thickness 0.15)
					)
					(justify left bottom)
					(hide yes)
				)
			)
			(property "Author" "Antmicro"
				(at 20.32 -27.94 0)
				(effects
					(font
						(size 1.27 1.27)
						(thickness 0.15)
					)
					(justify left bottom)
					(hide yes)
				)
			)
			(property "Val" "0R"
				(at 20.32 -7.62 0)
				(effects
					(font
						(size 1.27 1.27)
						(thickness 0.15)
					)
					(justify left bottom)
				)
			)
			(property "Tolerance" "~"
				(at 20.32 -10.16 0)
				(effects
					(font
						(size 1.27 1.27)
					)
					(justify left bottom)
					(hide yes)
				)
			)
			(property "Current" "1A"
				(at 20.32 -30.48 0)
				(effects
					(font
						(size 1.27 1.27)
						(thickness 0.15)
					)
					(justify left bottom)
					(hide yes)
				)
			)
			(property "ki_keywords" "0402, SMT, RESISTOR, PASSIVE"
				(at 0 0 0)
				(effects
					(font
						(size 1.27 1.27)
					)
					(hide yes)
				)
			)
			(symbol "R_0R_0402_0_1"
				(rectangle
					(start 0.635 0.889)
					(end 4.445 -0.889)
					(stroke
						(width 0.254)
						(type default)
					)
					(fill
						(type none)
					)
				)
			)
			(symbol "R_0R_0402_1_1"
				(pin passive line
					(at 0 0 0)
					(length 0.635)
					(name "~"
						(effects
							(font
								(size 1.27 1.27)
							)
						)
					)
					(number "1"
						(effects
							(font
								(size 1.27 1.27)
							)
						)
					)
				)
				(pin passive line
					(at 5.08 0 180)
					(length 0.635)
					(name "~"
						(effects
							(font
								(size 1.27 1.27)
							)
						)
					)
					(number "2"
						(effects
							(font
								(size 1.27 1.27)
							)
						)
					)
				)
			)
		)
	(symbol "TestPoints:TP_1.5mm_SMD"
			(pin_names
				(hide yes)
			)
			(exclude_from_sim no)
			(in_bom no)
			(on_board yes)
			(property "Reference" "TP"
				(at 15.24 -5.08 0)
				(effects
					(font
						(size 1.27 1.27)
						(thickness 0.15)
					)
					(justify left bottom)
				)
			)
			(property "Value" "TP_1.5mm_SMD"
				(at 15.24 -7.62 0)
				(effects
					(font
						(size 1.27 1.27)
						(thickness 0.15)
					)
					(justify left bottom)
					(hide yes)
				)
			)
			(property "Footprint" "antmicro-footprints:TP_SMD_1.5mm"
				(at 15.24 -10.16 0)
				(effects
					(font
						(size 1.27 1.27)
						(thickness 0.15)
					)
					(justify left bottom)
					(hide yes)
				)
			)
			(property "Datasheet" ""
				(at 17.78 -12.7 0)
				(effects
					(font
						(size 1.27 1.27)
						(thickness 0.15)
					)
					(justify left bottom)
					(hide yes)
				)
			)
			(property "Description" "test point, SMT"
				(at 0 0 0)
				(effects
					(font
						(size 1.27 1.27)
					)
					(hide yes)
				)
			)
			(property "MPN" ""
				(at 0 0 0)
				(effects
					(font
						(size 1.27 1.27)
					)
					(hide yes)
				)
			)
			(property "Manufacturer" ""
				(at 0 0 0)
				(effects
					(font
						(size 1.27 1.27)
					)
					(hide yes)
				)
			)
			(property "Author" "Antmicro"
				(at 15.24 -15.24 0)
				(effects
					(font
						(size 1.27 1.27)
						(thickness 0.15)
					)
					(justify left bottom)
					(hide yes)
				)
			)
			(property "License" "Apache-2.0"
				(at 15.24 -17.78 0)
				(effects
					(font
						(size 1.27 1.27)
						(thickness 0.15)
					)
					(justify left bottom)
					(hide yes)
				)
			)
			(property "ki_keywords" "TESTPOINT"
				(at 0 0 0)
				(effects
					(font
						(size 1.27 1.27)
					)
					(hide yes)
				)
			)
			(symbol "TP_1.5mm_SMD_1_1"
				(circle
					(center 3.175 0)
					(radius 0.635)
					(stroke
						(width 0.254)
						(type default)
					)
					(fill
						(type none)
					)
				)
				(pin passive line
					(at 0 0 0)
					(length 2.54)
					(name "1"
						(effects
							(font
								(size 1.27 1.27)
							)
						)
					)
					(number "1"
						(effects
							(font
								(size 1.27 1.27)
							)
						)
					)
				)
			)
		)
	(symbol "antmicroResistors0402:R_0R_0402"
			(pin_numbers
				(hide yes)
			)
			(pin_names
				(hide yes)
			)
			(exclude_from_sim no)
			(in_bom yes)
			(on_board yes)
			(property "Reference" "R"
				(at 20.32 -5.08 0)
				(effects
					(font
						(size 1.27 1.27)
						(thickness 0.15)
					)
					(justify left bottom)
				)
			)
			(property "Value" "R_0R_0402"
				(at 20.32 -12.7 0)
				(effects
					(font
						(size 1.27 1.27)
						(thickness 0.15)
					)
					(justify left bottom)
					(hide yes)
				)
			)
			(property "Footprint" "antmicro-footprints:R_0402_1005Metric"
				(at 20.32 -15.24 0)
				(effects
					(font
						(size 1.27 1.27)
						(thickness 0.15)
					)
					(justify left bottom)
					(hide yes)
				)
			)
			(property "Datasheet" "https://industrial.panasonic.com/cdbs/www-data/pdf/RDA0000/AOA0000C301.pdf"
				(at 20.32 -17.78 0)
				(effects
					(font
						(size 1.27 1.27)
						(thickness 0.15)
					)
					(justify left bottom)
					(hide yes)
				)
			)
			(property "Description" "SMD Chip Resistor, Jumper, 0 ohm, 100 mW, 0402 [1005 Metric], Thick Film, General Purpose"
				(at 0 0 0)
				(effects
					(font
						(size 1.27 1.27)
					)
					(hide yes)
				)
			)
			(property "MPN" "ERJ2GE0R00X"
				(at 20.32 -20.32 0)
				(effects
					(font
						(size 1.27 1.27)
						(thickness 0.15)
					)
					(justify left bottom)
					(hide yes)
				)
			)
			(property "Manufacturer" "Panasonic"
				(at 20.32 -22.86 0)
				(effects
					(font
						(size 1.27 1.27)
						(thickness 0.15)
					)
					(justify left bottom)
					(hide yes)
				)
			)
			(property "License" "Apache-2.0"
				(at 20.32 -25.4 0)
				(effects
					(font
						(size 1.27 1.27)
						(thickness 0.15)
					)
					(justify left bottom)
					(hide yes)
				)
			)
			(property "Author" "Antmicro"
				(at 20.32 -27.94 0)
				(effects
					(font
						(size 1.27 1.27)
						(thickness 0.15)
					)
					(justify left bottom)
					(hide yes)
				)
			)
			(property "Val" "0R"
				(at 20.32 -7.62 0)
				(effects
					(font
						(size 1.27 1.27)
						(thickness 0.15)
					)
					(justify left bottom)
				)
			)
			(property "Tolerance" "~"
				(at 20.32 -10.16 0)
				(effects
					(font
						(size 1.27 1.27)
					)
					(justify left bottom)
					(hide yes)
				)
			)
			(property "Current" "1A"
				(at 20.32 -30.48 0)
				(effects
					(font
						(size 1.27 1.27)
						(thickness 0.15)
					)
					(justify left bottom)
					(hide yes)
				)
			)
			(property "ki_keywords" "0402, SMT, RESISTOR, PASSIVE"
				(at 0 0 0)
				(effects
					(font
						(size 1.27 1.27)
					)
					(hide yes)
				)
			)
			(symbol "R_0R_0402_0_1"
				(rectangle
					(start 0.635 0.889)
					(end 4.445 -0.889)
					(stroke
						(width 0.254)
						(type default)
					)
					(fill
						(type none)
					)
				)
			)
			(symbol "R_0R_0402_1_1"
				(pin passive line
					(at 0 0 0)
					(length 0.635)
					(name "~"
						(effects
							(font
								(size 1.27 1.27)
							)
						)
					)
					(number "1"
						(effects
							(font
								(size 1.27 1.27)
							)
						)
					)
				)
				(pin passive line
					(at 5.08 0 180)
					(length 0.635)
					(name "~"
						(effects
							(font
								(size 1.27 1.27)
							)
						)
					)
					(number "2"
						(effects
							(font
								(size 1.27 1.27)
							)
						)
					)
				)
			)
		)
	(symbol "antmicroResistorsmisc:R_0R_0201"
			(pin_numbers
				(hide yes)
			)
			(pin_names
				(hide yes)
			)
			(exclude_from_sim no)
			(in_bom yes)
			(on_board yes)
			(property "Reference" "R"
				(at 20.32 -5.08 0)
				(effects
					(font
						(size 1.27 1.27)
						(thickness 0.15)
					)
					(justify left bottom)
				)
			)
			(property "Value" "R_0R_0201"
				(at 20.32 -12.7 0)
				(effects
					(font
						(size 1.27 1.27)
						(thickness 0.15)
					)
					(justify left bottom)
					(hide yes)
				)
			)
			(property "Footprint" "antmicro-footprints:R_0201"
				(at 20.32 -15.24 0)
				(effects
					(font
						(size 1.27 1.27)
						(thickness 0.15)
					)
					(justify left bottom)
					(hide yes)
				)
			)
			(property "Datasheet" "https://www.bourns.com/docs/product-datasheets/cr.pdf"
				(at 20.32 -17.78 0)
				(effects
					(font
						(size 1.27 1.27)
						(thickness 0.15)
					)
					(justify left bottom)
					(hide yes)
				)
			)
			(property "Description" "SMD Chip Resistor"
				(at 0 0 0)
				(effects
					(font
						(size 1.27 1.27)
					)
					(hide yes)
				)
			)
			(property "MPN" "CR0201-FX-0R00GLF"
				(at 20.32 -20.32 0)
				(effects
					(font
						(size 1.27 1.27)
						(thickness 0.15)
					)
					(justify left bottom)
					(hide yes)
				)
			)
			(property "Manufacturer" "Bourns"
				(at 20.32 -22.86 0)
				(effects
					(font
						(size 1.27 1.27)
						(thickness 0.15)
					)
					(justify left bottom)
					(hide yes)
				)
			)
			(property "License" "Apache-2.0"
				(at 20.32 -25.4 0)
				(effects
					(font
						(size 1.27 1.27)
						(thickness 0.15)
					)
					(justify left bottom)
					(hide yes)
				)
			)
			(property "Author" "Antmicro"
				(at 20.32 -27.94 0)
				(effects
					(font
						(size 1.27 1.27)
						(thickness 0.15)
					)
					(justify left bottom)
					(hide yes)
				)
			)
			(property "Val" "0R"
				(at 20.32 -7.62 0)
				(effects
					(font
						(size 1.27 1.27)
						(thickness 0.15)
					)
					(justify left bottom)
				)
			)
			(property "Tolerance" "1%"
				(at 20.32 -10.16 0)
				(effects
					(font
						(size 1.27 1.27)
					)
					(justify left bottom)
					(hide yes)
				)
			)
			(property "ki_keywords" "0603, SMT, RESISTOR, PASSIVE"
				(at 0 0 0)
				(effects
					(font
						(size 1.27 1.27)
					)
					(hide yes)
				)
			)
			(symbol "R_0R_0201_0_1"
				(rectangle
					(start 0.635 0.889)
					(end 4.445 -0.889)
					(stroke
						(width 0.254)
						(type default)
					)
					(fill
						(type none)
					)
				)
			)
			(symbol "R_0R_0201_1_1"
				(pin passive line
					(at 0 0 0)
					(length 0.635)
					(name "~"
						(effects
							(font
								(size 1.27 1.27)
							)
						)
					)
					(number "1"
						(effects
							(font
								(size 1.27 1.27)
							)
						)
					)
				)
				(pin passive line
					(at 5.08 0 180)
					(length 0.635)
					(name "~"
						(effects
							(font
								(size 1.27 1.27)
							)
						)
					)
					(number "2"
						(effects
							(font
								(size 1.27 1.27)
							)
						)
					)
				)
			)
		)
	(symbol "antmicroTestPoints:TP_1mm_SMD"
			(pin_names
				(hide yes)
			)
			(exclude_from_sim no)
			(in_bom no)
			(on_board yes)
			(property "Reference" "TP"
				(at 15.24 -5.08 0)
				(effects
					(font
						(size 1.27 1.27)
						(thickness 0.15)
					)
					(justify left bottom)
				)
			)
			(property "Value" "TP_1mm_SMD"
				(at 15.24 -7.62 0)
				(effects
					(font
						(size 1.27 1.27)
						(thickness 0.15)
					)
					(justify left bottom)
					(hide yes)
				)
			)
			(property "Footprint" "antmicro-footprints:TP_SMD_1mm"
				(at 15.24 -10.16 0)
				(effects
					(font
						(size 1.27 1.27)
						(thickness 0.15)
					)
					(justify left bottom)
					(hide yes)
				)
			)
			(property "Datasheet" ""
				(at 17.78 -12.7 0)
				(effects
					(font
						(size 1.27 1.27)
						(thickness 0.15)
					)
					(justify left bottom)
					(hide yes)
				)
			)
			(property "Description" "Test point 1mm SMD"
				(at 0 0 0)
				(effects
					(font
						(size 1.27 1.27)
					)
					(hide yes)
				)
			)
			(property "MPN" ""
				(at 0 0 0)
				(effects
					(font
						(size 1.27 1.27)
					)
					(hide yes)
				)
			)
			(property "Manufacturer" ""
				(at 0 0 0)
				(effects
					(font
						(size 1.27 1.27)
					)
					(hide yes)
				)
			)
			(property "Author" "Antmicro"
				(at 15.24 -15.24 0)
				(effects
					(font
						(size 1.27 1.27)
						(thickness 0.15)
					)
					(justify left bottom)
					(hide yes)
				)
			)
			(property "License" "Apache-2.0"
				(at 15.24 -17.78 0)
				(effects
					(font
						(size 1.27 1.27)
						(thickness 0.15)
					)
					(justify left bottom)
					(hide yes)
				)
			)
			(property "ki_keywords" "TESTPOINT"
				(at 0 0 0)
				(effects
					(font
						(size 1.27 1.27)
					)
					(hide yes)
				)
			)
			(symbol "TP_1mm_SMD_1_1"
				(circle
					(center 3.175 0)
					(radius 0.635)
					(stroke
						(width 0.254)
						(type default)
					)
					(fill
						(type none)
					)
				)
				(pin passive line
					(at 0 0 0)
					(length 2.54)
					(name "1"
						(effects
							(font
								(size 1.27 1.27)
							)
						)
					)
					(number "1"
						(effects
							(font
								(size 1.27 1.27)
							)
						)
					)
				)
			)
		)
	(symbol "antmicropower:GND"
			(power)
			(pin_numbers
				(hide yes)
			)
			(pin_names
				(hide yes)
			)
			(exclude_from_sim no)
			(in_bom yes)
			(on_board yes)
			(property "Reference" "#PWR"
				(at 8.89 -2.54 0)
				(effects
					(font
						(size 1.27 1.27)
						(thickness 0.15)
					)
					(justify left bottom)
					(hide yes)
				)
			)
			(property "Value" "GND"
				(at 8.89 -5.08 0)
				(effects
					(font
						(size 1.27 1.27)
						(thickness 0.15)
					)
					(justify left bottom)
				)
			)
			(property "Footprint" ""
				(at 8.89 -7.62 0)
				(effects
					(font
						(size 1.27 1.27)
						(thickness 0.15)
					)
					(justify left bottom)
					(hide yes)
				)
			)
			(property "Datasheet" ""
				(at 8.89 -12.7 0)
				(effects
					(font
						(size 1.27 1.27)
						(thickness 0.15)
					)
					(justify left bottom)
					(hide yes)
				)
			)
			(property "Description" ""
				(at 0 0 0)
				(effects
					(font
						(size 1.27 1.27)
					)
					(hide yes)
				)
			)
			(property "Author" "Antmicro"
				(at 8.89 -7.62 0)
				(effects
					(font
						(size 1.27 1.27)
						(thickness 0.15)
					)
					(justify left bottom)
					(hide yes)
				)
			)
			(property "License" "Apache-2.0"
				(at 8.89 -10.16 0)
				(effects
					(font
						(size 1.27 1.27)
						(thickness 0.15)
					)
					(justify left bottom)
					(hide yes)
				)
			)
			(symbol "GND_1_1"
				(polyline
					(pts
						(xy 0 0) (xy 0 -1.27) (xy 1.27 -1.27) (xy 0 -2.54) (xy -1.27 -1.27) (xy 0 -1.27)
					)
					(stroke
						(width 0)
						(type default)
					)
					(fill
						(type none)
					)
				)
				(pin power_in line
					(at 0 0 270)
					(length 0)
					(name "GND"
						(effects
							(font
								(size 1.27 1.27)
							)
						)
					)
					(number "1"
						(effects
							(font
								(size 1.27 1.27)
							)
						)
					)
				)
			)
		)
	(symbol "power:+3V3"
			(power)
			(pin_numbers
				(hide yes)
			)
			(pin_names
				(hide yes)
			)
			(exclude_from_sim no)
			(in_bom yes)
			(on_board yes)
			(property "Reference" "#PWR"
				(at 15.24 0 0)
				(effects
					(font
						(size 1.27 1.27)
						(thickness 0.15)
					)
					(justify left bottom)
					(hide yes)
				)
			)
			(property "Value" "+3V3"
				(at -3.175 2.54 0)
				(effects
					(font
						(size 1.27 1.27)
						(thickness 0.15)
					)
					(justify left bottom)
				)
			)
			(property "Footprint" ""
				(at 15.24 -7.62 0)
				(effects
					(font
						(size 1.27 1.27)
						(thickness 0.15)
					)
					(justify left bottom)
					(hide yes)
				)
			)
			(property "Datasheet" ""
				(at 15.24 -10.16 0)
				(effects
					(font
						(size 1.27 1.27)
						(thickness 0.15)
					)
					(justify left bottom)
					(hide yes)
				)
			)
			(property "Description" ""
				(at 0 0 0)
				(effects
					(font
						(size 1.27 1.27)
					)
					(hide yes)
				)
			)
			(property "Author" "Antmicro"
				(at 15.24 -2.54 0)
				(effects
					(font
						(size 1.27 1.27)
						(thickness 0.15)
					)
					(justify left bottom)
					(hide yes)
				)
			)
			(property "License" "Apache-2.0"
				(at 15.24 -5.08 0)
				(effects
					(font
						(size 1.27 1.27)
						(thickness 0.15)
					)
					(justify left bottom)
					(hide yes)
				)
			)
			(symbol "+3V3_0_1"
				(polyline
					(pts
						(xy 0 2.54) (xy -0.762 1.27)
					)
					(stroke
						(width 0)
						(type default)
					)
					(fill
						(type none)
					)
				)
				(polyline
					(pts
						(xy 0 2.54) (xy 0.762 1.27)
					)
					(stroke
						(width 0)
						(type default)
					)
					(fill
						(type none)
					)
				)
				(polyline
					(pts
						(xy 0 0) (xy 0 2.54)
					)
					(stroke
						(width 0)
						(type default)
					)
					(fill
						(type none)
					)
				)
			)
			(symbol "+3V3_1_1"
				(pin power_in line
					(at 0 0 90)
					(length 0)
					(hide yes)
					(name "+3V3"
						(effects
							(font
								(size 1.27 1.27)
							)
						)
					)
					(number "1"
						(effects
							(font
								(size 1.27 1.27)
							)
						)
					)
				)
			)
		)
)
